# T6G (Grand Teton) — schematic netlist excerpt (pin names and nets, part order shuffled) for the footprints in the layout excerpt that follows; sources: Cadence DE-HDL packaged netlist, KiCad conversion of 04192023_DAF0TMB3IC0_F0TG_MB_C_brd_V02_OCP.brd

X28  TP_TDR_4P_FTS  TP_TDR_4P_DIP EMPTY  pkg TH  page 260
  S1  = TDR_DIFF_80_IN6_DN
  P1  = T1_GND
  P2  = T1_GND
  S2  = TDR_DIFF_80_IN6_DP

C2155  Q_CAP  22UF 4V 20% X6S  pkg C0402  page 68 : A = PVDDCR_SOC_P0 ; B = GND

(kicad_pcb
	(version 20260206)
	(generator "pcbnew")
	(generator_version "10.0")
	(general
		(thickness 1.6)
		(legacy_teardrops no)
	)
	(paper "A4")
	(title_block
		(title "04192023_DAF0TMB3IC0_F0TG_MB_C_brd_V02_OCP.brd")
		(comment 1 "Grand Teton / footprints 5568-5569 of 8354")
	)
	(layers
		(0 "F.Cu" signal "TOP")
		(4 "In1.Cu" signal "GND")
		(6 "In2.Cu" signal "IN1")
		(8 "In3.Cu" signal "GND1")
		(10 "In4.Cu" signal "IN2")
		(12 "In5.Cu" signal "GND2")
		(14 "In6.Cu" signal "IN3")
		(16 "In7.Cu" signal "GND3")
		(18 "In8.Cu" signal "VCC")
		(20 "In9.Cu" signal "VCC1")
		(22 "In10.Cu" signal "GND4")
		(24 "In11.Cu" signal "IN4")
		(26 "In12.Cu" signal "GND5")
		(28 "In13.Cu" signal "IN5")
		(30 "In14.Cu" signal "GND6")
		(32 "In15.Cu" signal "IN6")
		(34 "In16.Cu" signal "GND7")
		(2 "B.Cu" signal "BOTTOM")
		(9 "F.Adhes" user "F.Adhesive")
		(11 "B.Adhes" user "B.Adhesive")
		(13 "F.Paste" user "Package Geometry/Pastemask Top")
		(15 "B.Paste" user "Package Geometry/Pastemask Bottom")
		(5 "F.SilkS" user "Ref Des/Silkscreen Top")
		(7 "B.SilkS" user "Ref Des/Silkscreen Bottom")
		(1 "F.Mask" user "Board Geometry/Soldermask Top")
		(3 "B.Mask" user "Board Geometry/Soldermask Bottom")
		(17 "Dwgs.User" user "User.Drawings")
		(19 "Cmts.User" user "User.Comments")
		(21 "Eco1.User" user "User.Eco1")
		(23 "Eco2.User" user "User.Eco2")
		(25 "Edge.Cuts" user "Board Geometry/Outline")
		(27 "Margin" user)
		(31 "F.CrtYd" user "Package Geometry/Place Bound Top")
		(29 "B.CrtYd" user "Package Geometry/Place Bound Bottom")
		(35 "F.Fab" user "Ref Des/Assembly Top")
		(33 "B.Fab" user "Ref Des/Assembly Bottom")
	)
	(footprint ""
		(layer "B.Cu")
		(at 498.693948 -147.924266 90)
		(property "Reference" "X28"
			(at 0.956564 2.769362 270)
			(unlocked yes)
			(layer "B.SilkS")
			(effects
				(font
					(size 0.7874 0.5842)
					(thickness 0.1524)
				)
				(justify left mirror)
			)
		)
		(property "Value" ""
			(at 0 0 90)
			(layer "B.Fab")
			(effects
				(font
					(size 1.27 1.27)
				)
				(justify mirror)
			)
		)
		(property "Device Type" "TP_TDR_4P_FTS_TH-TP_TDR_4P_DIP,EMPTY,TP15"
			(at -1.30175 1.27 0)
			(unlocked yes)
			(layer "B.Fab")
			(hide yes)
			(effects
				(font
					(size 0.635 0.4064)
					(thickness 0.1524)
				)
				(justify mirror)
			)
		)
		(property "User Part Number" "N_A"
			(at -1.30175 1.27 0)
			(unlocked yes)
			(layer "Cmts.User")
			(hide yes)
			(effects
				(font
					(size 0.635 0.4064)
					(thickness 0.1524)
				)
				(justify mirror)
			)
		)
		(duplicate_pad_numbers_are_jumpers no)
		(fp_line
			(start 0 -1.27)
			(end 0 -0.635)
			(stroke
				(width 0.1524)
				(type default)
			)
			(layer "B.SilkS")
		)
		(fp_line
			(start -2.54 -1.27)
			(end 0 -1.27)
			(stroke
				(width 0.1524)
				(type default)
			)
			(layer "B.SilkS")
		)
		(fp_line
			(start -2.54 -1.1303)
			(end -2.54 -1.27)
			(stroke
				(width 0.1524)
				(type default)
			)
			(layer "B.SilkS")
		)
		(fp_line
			(start 0 0.635)
			(end 0 1.905)
			(stroke
				(width 0.1524)
				(type default)
			)
			(layer "B.SilkS")
		)
		(fp_line
			(start -2.54 1.4097)
			(end -2.54 1.1303)
			(stroke
				(width 0.1524)
				(type default)
			)
			(layer "B.SilkS")
		)
		(fp_line
			(start 0 3.175)
			(end 0 3.81)
			(stroke
				(width 0.1524)
				(type default)
			)
			(layer "B.SilkS")
		)
		(fp_line
			(start 0 3.81)
			(end -2.54 3.81)
			(stroke
				(width 0.1524)
				(type default)
			)
			(layer "B.SilkS")
		)
		(fp_line
			(start -2.54 3.81)
			(end -2.54 3.6703)
			(stroke
				(width 0.1524)
				(type default)
			)
			(layer "B.SilkS")
		)
		(fp_poly
			(pts
				(xy 2.285746 -0.762) (xy 2.285746 0.762) (xy 0.761746 0)
			)
			(stroke
				(width 0)
				(type default)
			)
			(fill yes)
			(layer "B.SilkS")
		)
		(fp_line
			(start 0 -1.27)
			(end 0 3.81)
			(stroke
				(width 0.1)
				(type default)
			)
			(layer "B.Fab")
		)
		(fp_line
			(start -2.54 -1.27)
			(end 0 -1.27)
			(stroke
				(width 0.1)
				(type default)
			)
			(layer "B.Fab")
		)
		(fp_line
			(start 0 3.81)
			(end -2.54 3.81)
			(stroke
				(width 0.1)
				(type default)
			)
			(layer "B.Fab")
		)
		(fp_line
			(start -2.54 3.81)
			(end -2.54 -1.27)
			(stroke
				(width 0.1)
				(type default)
			)
			(layer "B.Fab")
		)
		(fp_poly
			(pts
				(xy 0.761746 0) (xy 2.285746 -0.762) (xy 2.285746 0.762)
			)
			(stroke
				(width 0)
				(type default)
			)
			(fill yes)
			(layer "B.Fab")
		)
		(pad "1" thru_hole circle
			(at 0 0 270)
			(size 1.0033 1.0033)
			(drill 0.249936)
			(layers "*.Cu" "*.Mask")
			(remove_unused_layers no)
			(net "TDR_DIFF_80_IN6_DN")
			(clearance 0.10795)
			(padstack
				(mode front_inner_back)
				(layer "Inner"
					(shape circle)
					(size 0.8001 0.8001)
					(clearance 0.1524)
				)
				(layer "B.Cu"
					(shape circle)
					(size 1.0033 1.0033)
					(thermal_gap 0.10795)
					(clearance 0.10795)
				)
			)
		)
		(pad "2" thru_hole circle
			(at -2.54 0 270)
			(size 1.9939 1.9939)
			(drill 0.249936)
			(layers "*.Cu" "*.Mask")
			(remove_unused_layers no)
			(net "T1_GND")
			(clearance 0.10795)
			(padstack
				(mode front_inner_back)
				(layer "Inner"
					(shape circle)
					(size 0.8001 0.8001)
					(clearance 0.1524)
				)
				(layer "B.Cu"
					(shape circle)
					(size 1.9939 1.9939)
					(thermal_gap 0.10795)
					(clearance 0.10795)
				)
			)
		)
		(pad "3" thru_hole circle
			(at -2.54 2.54 270)
			(size 1.9939 1.9939)
			(drill 0.249936)
			(layers "*.Cu" "*.Mask")
			(remove_unused_layers no)
			(net "T1_GND")
			(clearance 0.10795)
			(padstack
				(mode front_inner_back)
				(layer "Inner"
					(shape circle)
					(size 0.8001 0.8001)
					(clearance 0.1524)
				)
				(layer "B.Cu"
					(shape circle)
					(size 1.9939 1.9939)
					(thermal_gap 0.10795)
					(clearance 0.10795)
				)
			)
		)
		(pad "4" thru_hole circle
			(at 0 2.54 270)
			(size 1.0033 1.0033)
			(drill 0.249936)
			(layers "*.Cu" "*.Mask")
			(remove_unused_layers no)
			(net "TDR_DIFF_80_IN6_DP")
			(clearance 0.10795)
			(padstack
				(mode front_inner_back)
				(layer "Inner"
					(shape circle)
					(size 0.8001 0.8001)
					(clearance 0.1524)
				)
				(layer "B.Cu"
					(shape circle)
					(size 1.0033 1.0033)
					(thermal_gap 0.10795)
					(clearance 0.10795)
				)
			)
		)
	)
	(footprint ""
		(layer "B.Cu")
		(at 364.165896 -256.012188 -90)
		(property "Reference" "C2155"
			(at 0 0 90)
			(layer "B.SilkS")
			(hide yes)
			(effects
				(font
					(size 1.27 1.27)
				)
				(justify mirror)
			)
		)
		(property "Value" ""
			(at 0 0 90)
			(layer "B.Fab")
			(effects
				(font
					(size 1.27 1.27)
				)
				(justify mirror)
			)
		)
		(duplicate_pad_numbers_are_jumpers no)
		(fp_line
			(start -0.7874 0.4064)
			(end 0.7874 0.4064)
			(stroke
				(width 0.1524)
				(type default)
			)
			(layer "B.SilkS")
		)
		(fp_line
			(start 0.7874 0.4064)
			(end 0.7874 -0.4064)
			(stroke
				(width 0.1524)
				(type default)
			)
			(layer "B.SilkS")
		)
		(fp_line
			(start -0.7874 -0.4064)
			(end -0.7874 0.4064)
			(stroke
				(width 0.1524)
				(type default)
			)
			(layer "B.SilkS")
		)
		(fp_line
			(start 0.7874 -0.4064)
			(end -0.7874 -0.4064)
			(stroke
				(width 0.1524)
				(type default)
			)
			(layer "B.SilkS")
		)
		(fp_line
			(start -0.67945 0.3048)
			(end -0.120396 0.3048)
			(stroke
				(width 0.1)
				(type default)
			)
			(layer "B.Fab")
		)
		(fp_line
			(start -0.120396 0.3048)
			(end -0.120396 0.2794)
			(stroke
				(width 0.1)
				(type default)
			)
			(layer "B.Fab")
		)
		(fp_line
			(start 0.12065 0.3048)
			(end 0.67945 0.3048)
			(stroke
				(width 0.1)
				(type default)
			)
			(layer "B.Fab")
		)
		(fp_line
			(start 0.67945 0.3048)
			(end 0.67945 -0.305054)
			(stroke
				(width 0.1)
				(type default)
			)
			(layer "B.Fab")
		)
		(fp_line
			(start -0.120396 0.2794)
			(end 0.12065 0.2794)
			(stroke
				(width 0.1)
				(type default)
			)
			(layer "B.Fab")
		)
		(fp_line
			(start 0.12065 0.2794)
			(end 0.12065 0.3048)
			(stroke
				(width 0.1)
				(type default)
			)
			(layer "B.Fab")
		)
		(fp_line
			(start -0.12065 -0.2794)
			(end -0.12065 -0.3048)
			(stroke
				(width 0.1)
				(type default)
			)
			(layer "B.Fab")
		)
		(fp_line
			(start 0.12065 -0.2794)
			(end -0.12065 -0.2794)
			(stroke
				(width 0.1)
				(type default)
			)
			(layer "B.Fab")
		)
		(fp_line
			(start -0.67945 -0.3048)
			(end -0.67945 0.3048)
			(stroke
				(width 0.1)
				(type default)
			)
			(layer "B.Fab")
		)
		(fp_line
			(start -0.12065 -0.3048)
			(end -0.67945 -0.3048)
			(stroke
				(width 0.1)
				(type default)
			)
			(layer "B.Fab")
		)
		(fp_line
			(start 0.12065 -0.305054)
			(end 0.12065 -0.2794)
			(stroke
				(width 0.1)
				(type default)
			)
			(layer "B.Fab")
		)
		(fp_line
			(start 0.67945 -0.305054)
			(end 0.12065 -0.305054)
			(stroke
				(width 0.1)
				(type default)
			)
			(layer "B.Fab")
		)
		(pad "1" smd circle
			(at 0.40005 0 90)
			(size 0 0)
			(layers "B.Cu" "B.Mask" "B.Paste")
			(net "PVDDCR_SOC_P0")
		)
		(pad "2" smd circle
			(at -0.40005 0 90)
			(size 0 0)
			(layers "B.Cu" "B.Mask" "B.Paste")
			(net "GND")
		)
	)
)
